M48
INCH,TZ
T01C.012
T02C.016
T03C.035
T04C.04
T05C.041
T06C.138
T07C.158
T08C.199
T09C.099
T10C.115
T11C.126
T12C.14
T13C.142
;LEADER: 12 
;HEADER: 
;CODE  : ASCII 
;FILE  : 12433-2a-1-4.drl for board 12433-2a.brd ... layers TOP and BOTTOM
;T01 Holesize 1. = 12.000000 Tolerance = +0.000000/-0.000000 PLATED MILS Quantity = 499
;T02 Holesize 2. = 16.000000 Tolerance = +0.000000/-0.000000 PLATED MILS Quantity = 1578
;T03 Holesize 3. = 35.000000 Tolerance = +0.000000/-0.000000 PLATED MILS Quantity = 18
;T04 Holesize 4. = 40.000000 Tolerance = +0.000000/-0.000000 PLATED MILS Quantity = 36
;T05 Holesize 5. = 41.000000 Tolerance = +0.000000/-0.000000 PLATED MILS Quantity = 104
;T06 Holesize 6. = 138.000000 Tolerance = +0.000000/-0.000000 PLATED MILS Quantity = 6
;T07 Holesize 7. = 158.000000 Tolerance = +0.000000/-0.000000 PLATED MILS Quantity = 2
;T08 Holesize 8. = 199.000000 Tolerance = +0.000000/-0.000000 PLATED MILS Quantity = 5
;T09 Holesize 9. = 99.000000 Tolerance = +0.000000/-0.000000 NON_PLATED MILS Quantity = 4
;T10 Holesize 10. = 115.000000 Tolerance = +0.000000/-0.000000 NON_PLATED MILS Quantity = 6
;T11 Holesize 11. = 126.000000 Tolerance = +0.000000/-0.000000 NON_PLATED MILS Quantity = 4
;T12 Holesize 12. = 140.000000 Tolerance = +0.000000/-0.000000 NON_PLATED MILS Quantity = 4
;T13 Holesize 13. = 142.000000 Tolerance = +0.000000/-0.000000 NON_PLATED MILS Quantity = 12
%
G90
T01
X64500Y53000
X84500Y56500
X89500Y49500
X97000Y51500
X115500Y59500
X149500Y52000
X115000Y76500
X109500Y62000
X109000Y76500
X99500Y61000
X98500Y73000
X92500
X91500Y88500
X88253Y65500
X81500Y75500
X79000Y65500
X75000Y67500
X74000Y60500
X70454Y60031
X64000Y67553
X63500Y63500
X91000Y97000
X91500Y92500
X93000Y107000
X93500Y101500
X93900Y111800
X104500Y101000
X112000
X59600Y125800
X201500Y165000
X75300Y155300
X65000Y166300
X63500Y179300
X60350Y151950
X53000Y171500
X52700Y162300
X52500Y175200
X49924Y153261
X43400Y174325
X39300Y175500
X32425Y177900
X39300Y181100
X43700Y181200
X47800Y199200
X49700Y209700
X53400Y191300
X53500Y199700
X54200Y207850
X64000Y199700
X64400Y183400
X65200Y207850
X70500Y190200
X71400Y208150
X38000Y228500
X41100Y231000
X42720Y233990
X51700Y234800
X54200Y220700
X54400Y217000
X57424Y232974
X61300Y229400
X65000Y235400
X69400Y226100
X69900Y236600
X70600Y217600
X72100Y221700
X74800Y231800
X75300Y211300
X77900Y229034
X85676Y231100
X117600Y234900
X122100Y230100
X127200Y246000
X70600Y250500
X68000Y268000
X65000Y241500
X58936Y256289
X57500Y268500
X52500Y248500
X50800Y266400
X48500Y248600
X42500Y254100
Y260200
X36000Y260386
X26450Y274750
X32600Y290500
X32675Y299500
X34200Y284800
X43400Y272300
X45800Y277800
X54000Y275600
X60300Y275700
X25500Y321200
X21600Y333800
X23100Y342400
X23400Y353500
X29500Y343500
Y410500
X191400Y432405
X146960Y432400
X135500Y441000
X122500
X78000Y429500
X34000Y448000
X14000Y476000
X33200Y468900
X108100Y477650
X142000Y478500
X165300Y481100
X144000Y509500
X166100Y527900
X162500
X147000Y529900
X132500Y539621
X91300Y528200
X87700Y528000
X72397Y528297
X71445Y532192
X52100Y513100
X51000Y529500
X46500Y511000
X46000Y516000
X28800Y533700
X5304Y528900
Y548800
X49700Y568900
X65000Y561500
X66000Y550500
X70350Y558850
X77800Y540300
X92200Y553800
X102700Y541000
X106300Y553200
X108900Y541300
X110400Y550800
X115300Y551800
X119800Y568300
X124200Y568400
X135000Y561500
X142500Y550000
X156300Y552100
X159850Y541800
X160000Y562500
X182588Y542288
X5094Y574500
X23450Y577491
X25148Y570800
X27000Y573800
X29500Y586500
X33450Y574300
X54600Y573400
X63400Y581400
X78400Y583700
X87000Y591000
X88000Y586500
X89000Y595000
X91300Y577000
X96000Y588000
X101000Y583000
X113655Y599363
X116000Y596900
X121000Y581500
X122300Y575000
X124900Y582000
X128900Y580500
X129000Y597000
X133500Y575500
Y582000
X134600Y586700
X137000Y589900
X142100Y581400
X145800Y594400
X147900Y588100
X154600Y581500
X159250Y590250
X174196Y628196
X202210Y638500
X139200Y653900
X138900Y650100
X131135Y639554
X122500Y653650
X117400Y653100
X87000Y648000
X84200Y643865
X82000Y652000
X66200Y653500
X39800Y681400
X52500Y682500
X53000Y673500
X60500Y682540
X60900Y670200
X64000Y666600
X76100Y686900
X83850Y678109
X86597Y681103
X100200Y663900
X109005Y665890
X114000Y663350
X118127Y663400
X134600Y665600
X142648Y665429
X149000Y677000
X150978Y687775
X155200Y679500
X157500Y664500
X161000Y674000
X202500Y666000
X201500Y691500
X175100Y710000
X165900Y717300
X165433Y692372
X161500Y691700
X153192Y705890
X150700Y691700
X147000Y703000
X130000Y700500
X122500
X114500
X106000Y709000
X105500Y702500
X98000Y703000
Y698500
Y708000
X93000Y698500
X91250Y704700
X88500Y700000
X78494Y697835
X75571Y692496
X57684Y697639
X53000Y695100
X49500Y703500
X46500Y705500
X44500Y697500
X43388Y694286
X4594Y714000
Y749000
X69000Y726800
X71500Y735500
X73000Y728000
X73500Y732000
X86500Y723500
X113500Y729000
Y721000
Y736000
Y747000
X119500Y746500
Y739500
X130000Y746000
X146000Y738000
Y726000
X161500Y747500
X161600Y739800
X170000Y745500
X201500Y726500
X202500Y755500
X201500Y777000
X166500Y775500
X166000Y760000
Y751500
X161500Y778000
Y759000
Y768000
X158600Y752600
X146000Y765500
Y755000
X130000Y764000
Y753000
X119500Y757500
X113500Y756000
X146000Y796500
Y782500
X201389Y797000
X202500Y822000
X174000Y834500
X168000Y830000
X162000Y817500
X146500Y812000
X146000Y824000
X114900Y824100
X98900Y822900
X72400
X61207Y828350
X51200Y827000
X57500Y844500
X100300Y841000
X102300Y863438
X106404Y840700
X107164Y862285
X111500Y851600
X113400Y862200
X118700Y840700
X180000Y856000
X202000Y859500
X202500Y846500
X202000Y875000
Y890000
X180000Y872500
X179500Y884000
X157800Y898000
X101500Y874200
X67200Y888800
X64600Y882700
X61600Y885200
X59500Y881600
X57500Y890300
X56000Y885500
X55700Y880000
X49600Y889400
X54300Y915500
X147500Y900500
X179900Y900900
Y925700
X180000Y912500
X202000Y918000
X202210Y903500
X202500Y945500
X201500Y931500
X179800Y941400
X152747Y952474
X149772Y954121
X146500Y953030
X143000Y953032
X202500Y977500
Y962000
X180500Y973200
X180000Y960400
X163200Y985200
X163100Y978600
X155000Y974500
X150500Y976500
X125400Y983600
X94000Y971800
X83500Y976300
Y972800
X83000Y979800
X57500Y987800
Y984300
X51000Y1018000
X53800Y1006200
X54000Y996500
X70800Y990500
X97300Y990800
X125400Y992000
X127200Y1015200
X149800Y1008700
X179000Y1005000
X201500Y991000
Y1019000
X202500Y1006000
X202000Y1037000
X163000Y1042500
X155500Y1030000
X153500Y1033500
X151500Y1030500
X104000Y1049500
X56000Y1021500
X54500Y1035500
X53500Y1025500
X104000Y1062500
X159500Y1062000
X201389Y1067000
X202000Y1052000
X201500Y1082500
X64500Y1099000
X37500Y1099823
X82094Y1112500
X195000Y1112000
X201500Y1147000
X73163Y1158780
X70500Y1161500
X68800Y1178800
X71100Y1171000
X105000Y1181000
X202500Y1179000
X202000Y1212000
Y1246000
X119000Y1255968
X119500Y1261000
X202500Y1280000
X201500Y1306500
Y1359500
Y1350000
X5000Y1355000
X39400Y1381300
X44500Y1380500
X45500Y1400000
X100860Y1402260
X111000Y1394000
X125000Y1398500
X125100Y1402500
X128700Y1408000
X146500Y1397100
X155900
X201700Y1388300
X201500Y1413000
X201389Y1425500
X169000Y1426750
X151500Y1438500
X142500Y1420500
X139900Y1415100
X135601Y1416200
X134500Y1420000
X132000Y1436500
X131174Y1412700
X110000Y1429500
X89000Y1428171
X45000Y1428000
X83200Y1455500
X157500Y1454800
X158500Y1466500
X202210Y1462000
X202400Y1444000
X153500Y1496500
X147500Y1498000
X142000Y1494800
X132300Y1491100
X112750Y1491250
X80000Y1472000
X26700Y1529800
X36400Y1523400
X109000Y1506500
X113000
X117000
X121000
X125000
X128999Y1506499
X133000Y1505500
X135008Y1508245
X194500Y1510000
Y1505500
X196500Y1572000
X177500Y1569500
X143518Y1567520
X108500Y1569000
X67700Y1568700
X28000Y1596800
X38400Y1596700
X42700Y1606000
X83000Y1619703
X83050Y1616000
X113200Y1619300
X196500Y1606500
X192650Y1641500
X192500Y1648000
X173270Y1626517
X169876Y1626303
X141500Y1621600
X141300Y1625000
X113200Y1622800
X43500Y1620700
X43300Y1646600
X31400Y1648200
X13300Y1644300
X10500Y1648800
X35500Y1670500
X42500Y1673000
X43600Y1668300
X44500Y1678000
X192500Y1653000
X45500Y1690000
X44100Y1685200
X41500Y1692000
X40300Y1703900
X34000Y1691500
X19200Y1707000
X13300Y1689600
X19542Y1710518
X29100Y1721550
X25000Y1763800
X52500Y1756000
X45300Y1776300
X22000Y1787800
X41500Y1889500
X47000Y1886200
X55900Y1881500
X62000Y1877000
X65300Y1886600
X152500Y1883100
X200500Y1876500
X201200Y1890500
X201100Y1908800
X177700Y1912800
X162100Y1912000
X151900Y1891400
X146300Y1913700
X133500Y1906500
X60300Y1892300
X57900Y1899800
X38700Y1893800
X27400Y1899400
X79900Y1923000
X91100Y1922800
X104600Y1923400
X128900Y1923300
X142400Y1923800
X157900Y1923100
X170000Y1920500
X176700Y1923900
X184500Y1920500
T02
X20000Y6000
X8594Y6500
X17000Y36500
X29500Y53000
X5594Y53500
Y87000
X26000
X14500Y100500
X4500Y105500
X14500Y112500
X4594Y120500
X23500Y124000
X15000Y131500
X5000Y137500
X14000Y141000
X5594Y153500
X4500Y170500
X16500Y175000
X27000Y182000
X14000Y184000
X4594Y187500
X22500Y190000
X29700Y191400
X12500Y197500
X29000Y200500
X4500Y202500
X24000Y212000
X13000Y212500
X5000Y221000
X13500Y230500
X4594Y234000
X21500Y241500
X13000Y244000
X5000Y247500
X28050Y256950
X6094Y257000
X12500Y266500
X19721Y267203
X5500Y269500
X5094Y278000
X13500Y279000
Y295000
X5500Y295500
X13500Y303500
X5594Y312000
X13000Y321000
X4900Y328000
X5304Y342500
X4800Y356200
X23700Y363900
X29500Y364500
X27000Y371000
X6500Y375000
X27000Y377500
Y384000
Y389500
X4594Y396500
X5000Y408500
X23800Y410700
X4594Y421000
X26000Y432500
X5304Y434500
X26500Y440000
X5304Y440500
Y444500
X4700Y458200
X5094Y469500
X5000Y486500
Y495000
X13510Y597990
X5094Y600000
X18000Y608000
X6000Y612000
X14000Y614000
X4594Y625000
X6000Y646000
X26000Y656500
X14000Y659000
X5304Y661000
X23000Y677500
X8000Y678000
X5594Y688500
X20000Y696000
X6000Y698000
X28000Y706000
X6000Y706500
X18000Y712000
X6000Y722000
X18000Y724000
X6000Y730500
X26000Y732000
X18000Y732500
X22000Y746000
X27000Y750000
X24000Y756000
X5594Y778000
X16100Y794600
X6500Y799000
X9500Y804000
X10000Y811500
X16000Y814000
X6094Y819500
X16000Y828000
X26053Y828247
X4500Y833500
X16000Y842000
X5594Y844500
X24000Y846000
X24500Y853500
X16000Y856000
X4500Y857500
X23053Y861247
X5594Y869000
X18000Y870000
X5000Y883500
X18000Y884000
X18500Y896500
X5094Y897500
X16000Y906000
X4500Y913000
X18000Y920000
X5304Y926000
X18000Y934000
X26053Y938247
X4500Y941500
X16000Y948000
X4594Y954000
X16000Y962000
X4500Y970000
X25053Y971247
X16000Y976000
X5594Y984500
X16000Y990000
X28000Y992000
X4500Y997000
X16000Y1000000
X26000Y1010000
X4594Y1013500
X16000Y1014000
X27553Y1029247
X4500Y1029500
X16000Y1032000
X4594Y1041500
X16000Y1046000
X6000Y1058000
X14000Y1060000
X28000Y1072000
X14000Y1074000
X5094Y1074500
X14000Y1086000
X26100Y1088600
X6000Y1096000
X27218Y1097000
X14000Y1100000
X16000Y1110000
X6000Y1118000
X16000Y1124000
X26600Y1132400
X16000Y1134000
X6000Y1138000
X16000Y1148000
X6000Y1152000
X24553Y1153247
X16000Y1162000
X4594Y1169500
X16000Y1176000
X24000Y1180000
X5304Y1208000
X22000Y1232000
X8500Y1237000
X16000Y1244000
X6000Y1252000
X16000Y1262000
X28000Y1266000
X5094Y1268500
X12000Y1274000
X17700Y1283000
X28000Y1286000
X12000Y1294000
X28000Y1300000
X6500Y1302000
X19800Y1315400
X6000Y1318000
X28000Y1320000
X13500Y1365000
X8000Y1368000
X7500Y1376500
X4594Y1382000
X5304Y1409400
X4594Y1435500
X4800Y1460700
X4600Y1484800
X29500Y1495800
X5304Y1504100
Y1522100
Y1540500
X26900Y1547900
Y1559100
X26600Y1570100
X5304Y1576200
X26700Y1579800
X4594Y1607500
Y1632000
X7500Y1640200
X5304Y1659000
X19250Y1663100
X29000Y1671000
X4700Y1676100
X4594Y1691000
X13900Y1706200
X4900Y1708000
X5304Y1723500
X13100Y1728900
Y1742600
X4594Y1751000
X12600Y1753800
X12900Y1765200
X4594Y1775000
X12500Y1782500
X12600Y1792800
X14500Y1832500
X29000Y1841000
X14500Y1842000
X4594Y1850000
X15000Y1854900
X14500Y1863500
X5000Y1864100
X18600Y1871400
X28000Y1876500
X4594Y1878500
X27500Y1883500
X4594Y1902000
X5094Y1921000
X24800Y1926500
X13100Y1933900
X4500Y1936000
X15500Y1942500
X5094Y1944500
X16100Y1950700
X12500Y1959000
X6500Y1962000
X25000Y1962500
X34500Y1963200
X55300Y1959100
X41100Y1957500
X49053Y1951747
X43500Y1945000
X35000Y1933500
X45100Y1933400
X54000Y1928500
X35300Y1925300
X46000Y1923000
X36500Y1900500
X54500Y1889500
X39700Y1869700
X46500Y1865500
X46700Y1857700
X46500Y1850200
Y1844000
X44500Y1833500
X39179Y1792306
X42000Y1784400
X38800Y1775000
X56500Y1769300
X36700Y1764700
X53000Y1750500
X41600Y1746900
X48400
X44900Y1740300
X55500Y1735500
X30000Y1731000
X44600Y1724400
X55500Y1723500
X56000Y1712500
X44900Y1706800
X56000Y1704500
X42500Y1699500
X56000Y1695000
X59500Y1667000
X53500Y1659000
X54000Y1646500
X43200Y1634800
X57500Y1634500
X55400Y1613300
X58500Y1607700
X50600Y1601300
X55300Y1601100
X50600Y1595300
X55300Y1595100
X44400Y1592100
X50600Y1589300
X55300Y1589100
X33100Y1587400
X50600Y1582800
X55300Y1582600
X38300Y1579600
X54500Y1574000
X37900Y1570000
X57000Y1568500
X45300Y1563600
X57500Y1562000
X38300Y1561800
X38800Y1541700
X54300Y1541200
X46600Y1541100
X59500Y1541000
X45900Y1532800
X45400Y1523800
X53500Y1519000
X58500
X43300Y1518500
X49500Y1505000
X42700Y1500000
X46500Y1484900
X34000Y1477600
X59000Y1472000
X34000Y1465900
X58100Y1459300
X49100Y1448400
X59000Y1444500
X42600Y1444200
X53100Y1430700
X49000Y1413300
X58800Y1412400
X39500Y1407900
X30800Y1403900
X56700Y1400100
X31500Y1397500
X32000Y1391500
X48900Y1390500
X55600Y1381700
X52500Y1368500
X44000Y1340000
X39000Y1333500
X54000Y1330000
X44000Y1326000
X50000Y1318000
X58000Y1312000
X34000
X44000Y1306000
X40000Y1298000
X52000Y1296300
X58000Y1292000
X42000Y1290000
X40000Y1278000
X58000Y1272000
X42000Y1266000
X50100Y1261500
X58000Y1250000
X50000Y1244000
X42000Y1242000
X30000Y1240000
X51800Y1231600
X39500Y1231000
X58000Y1222000
X31500
X46000Y1218000
X58000Y1206000
X44000Y1194000
X54000Y1184000
X40000Y1156000
X34000Y1144000
X40000Y1136000
X37500Y1118900
X32000Y1114000
X39300Y1105800
X34000Y1102000
X33550Y1080100
X34000Y1072000
X33600Y1029900
X31600Y1024300
X34000Y1017500
Y1008000
X37700Y991600
X34000Y984000
Y974500
X55500Y968000
X33500Y962500
X55500Y955500
X33500Y953000
X34000Y944000
X56500Y940000
X34000Y934500
X41000Y931899
X37500Y912000
Y907500
X40900Y901500
X32000Y886000
X47000Y877600
X32000Y872000
Y858000
X48100Y853400
X46000Y848000
X32000Y844000
X46000Y834000
X38000
X45600Y827500
X38000Y820000
X30500Y819500
X48000Y816000
X42000Y802000
X47600Y796800
X42000Y788000
X44000Y782000
X30000
X50000Y749000
X31000Y747000
X40000Y746500
X36000Y730000
X46000Y726000
X50000Y712500
X31000Y700500
X56710Y681069
X43281Y674991
X39096Y674917
X32000Y666000
X40000Y659000
X56800Y576950
X34100Y566600
X36000Y554000
X51700Y522500
X42500Y493000
X50100
X46000Y490500
X58100Y431900
X58000Y426000
Y417500
Y408000
Y400000
Y390000
X51900Y145700
X51700Y131700
X30800Y130300
X37000Y124000
X52000Y115600
X34400Y95300
X51500Y53000
X32000Y40000
X43000Y27000
X49000Y18500
X40594Y6000
X31500Y5500
X53000Y5000
X63594Y7000
X64000Y17000
X63594Y25500
X64500Y40000
X85000Y45000
X74000
X63098Y119103
X71000Y131859
X62598Y141103
X73500Y146000
X60800Y147700
X86000Y152000
X69000Y153000
X68000Y286000
Y296000
X76000
X86000
X68000Y304000
Y312000
Y320000
X74000Y390000
X66000
X74000Y400000
X66000
X74000Y408000
X66000
X86400Y410500
X81000
X66000Y418000
X74000
X73700Y423000
X66000Y426000
X88500Y426500
X84500Y433000
X68500Y434300
X63096Y434540
X89800Y446000
X64000Y446500
Y451000
X89800Y452900
X64000Y455500
X89800Y459000
X64000Y460000
X63300Y464400
X89800Y464800
X62600Y468500
X62500Y472900
Y477000
X78200Y481700
X82000Y483600
X78200Y501000
X71900
X85000Y506400
X78500Y506700
X71800Y506900
X84500Y514400
X72000Y514800
X78000
X79400Y521800
X72100
X74942Y530983
X79122Y565700
X69800Y574200
X79458Y578758
X87595Y581300
X72500Y595900
X88967Y659749
X86443Y662853
X84504Y666353
X80900Y668400
X74100Y669398
X87310Y676796
X69100Y698006
X71800Y701300
X82000Y806500
X82500Y814000
X78300Y832600
X81500Y837500
X87000Y839500
X77600Y849100
X79000Y857000
X62500Y862000
X77000Y863000
Y871500
X61500Y876500
X78000Y878500
X83400Y878600
X78300Y893900
X85500Y903000
X77500Y907000
X70000Y914500
X85500Y915000
X77500Y917000
X62500Y924500
X70000Y925500
X76500Y927000
X86500Y932000
X75500Y936500
X61500Y938500
X69500Y939000
X81500Y940000
X88500Y940500
X64000Y980500
X87000Y997500
X76400Y999100
X87000Y1064000
X83500Y1067000
Y1072000
Y1076500
X77293Y1129729
X74000Y1132000
X67302Y1133490
X79044Y1144112
X78292Y1148041
X66000Y1149500
X64500Y1165700
X89000Y1167400
X61000Y1173000
X60000Y1194000
X84000Y1352000
X72000Y1360000
X61000Y1363500
X83800Y1365900
X71800Y1373900
X70500Y1378500
X61500Y1380000
X81500Y1382000
X60900Y1390500
X83800Y1391900
X72900Y1393600
X69400Y1402900
X81500Y1404000
X74900Y1408800
X89700Y1409700
X81500Y1416500
X68800Y1417800
X75600Y1420300
X60600Y1423600
X76200Y1430700
X87200Y1431900
X66500Y1433500
X87300Y1436000
X79000Y1436400
X87200Y1440000
X70400Y1444500
X87700Y1446500
X77000Y1449000
X86900Y1451000
X68500Y1454600
X74500Y1461800
X83500Y1469500
X72300Y1469800
X72700Y1480500
X63000Y1482300
X85000Y1490000
X73000Y1491200
X64100Y1495400
X72000Y1514000
X85200Y1515000
X87900Y1523400
X80000Y1531600
X73900Y1535900
X68700Y1603900
X71600Y1607700
X86000Y1634000
X64000
X76000
Y1646000
X86000
X64500
Y1658500
X75500Y1659500
X86000
X70000Y1668000
X86000Y1669000
Y1679000
X75500
X69000Y1684500
X80500
X62500Y1691500
X72500Y1699000
X62500Y1700000
X86500Y1700110
X62500Y1709000
X86500Y1713610
X72500Y1717000
X65000Y1724000
X86500Y1726000
X60000Y1730000
X72500Y1733000
X65000Y1735000
Y1742500
Y1749000
X64500Y1758500
X71500Y1760000
X79000Y1766500
X65000Y1768000
X87000Y1774110
X88500Y1785000
X65000Y1790000
X86500Y1793110
X72000Y1798000
X64500Y1801500
X81000Y1802000
X64500Y1812000
X73000Y1813000
X64500Y1821500
X72500Y1830000
X64000Y1834000
X75500Y1838500
X85100Y1844500
X64000
X73000Y1847000
X85700Y1852300
X63500Y1856000
Y1863000
X61500Y1922500
X63500Y1928000
X63594Y1935500
X61600Y1954700
X63500Y1963000
X118000Y1922000
X116948Y1892000
X114500Y1862500
X106500
X99500
X108500Y1851610
X97000Y1850500
X114000Y1843500
X110500Y1801000
X119500Y1796500
X97500Y1796000
X107768Y1789110
X98000Y1786000
X108268Y1777300
X97500Y1775500
X111500Y1768500
X119500Y1760000
Y1747110
X117500Y1732000
X108500Y1727000
X119500Y1725110
X109500Y1719500
X98500Y1717000
X119500Y1710110
X110000Y1709500
X99000Y1707000
X109500Y1699000
X119500Y1696610
X98500Y1696500
X91000Y1685000
X103000
X112500
X97500Y1679500
X117500Y1679000
X107500
X97000Y1669000
X107000
X117500
X107000Y1659500
X97000
X117500
X96000Y1646000
X118000
X108000
X106000Y1634000
X96500
X117000Y1633500
X116000Y1612000
X104000Y1605500
X94500
X113500
X116000Y1600000
Y1592000
Y1584000
Y1576000
X115900Y1569700
X102000Y1568000
X94000
X114000Y1564000
X94000Y1562000
X102000
X114000Y1558000
X94000Y1556000
X102000
X114000Y1552000
X94000Y1550000
X102000
X114000Y1546000
X102000Y1544000
X111500Y1537500
X119000Y1529500
X93000Y1518700
X94000Y1514000
X97000Y1503100
X91300Y1488600
X99170Y1485790
X93500Y1482700
X103700Y1470300
X95500Y1468000
X117195Y1456070
X99800Y1455600
X113024Y1452079
X117024Y1452000
X117122Y1448001
X109500Y1438000
X117000Y1435200
X98500Y1428400
X94000Y1427800
X110000Y1418000
X99600Y1416500
X105500Y1415000
X97500Y1412000
X93600Y1407100
X93800Y1393200
X100500Y1389000
Y1384500
X93800Y1379900
X114000Y1376000
X114500Y1370500
X94000Y1366000
X115800Y1363900
X93800Y1353900
X116000Y1350000
X94000Y1340000
X113800Y1331900
X90800Y1331200
X97800Y1327900
X114000Y1318000
X91500Y1314500
X99500Y1310000
X114500Y1296500
X92000Y1295500
X99500Y1294000
X113800Y1287900
X98000Y1282000
X114000Y1274000
X119000Y1269000
X99000Y1265500
X92000Y1254000
X117500Y1251000
X112000Y1250500
X119300Y1245400
X103000Y1244900
X112000Y1244500
X92000Y1241500
X119500Y1231500
X91500Y1229000
X103500
X104500Y1219500
X119300Y1219400
X92000Y1214500
X104500Y1208000
X119500Y1205500
X91500Y1200000
X105000Y1196000
X119300Y1191400
X94000Y1189000
X119500Y1177500
X118500Y1166000
X97500Y1132500
X97000Y1127500
X106000
X101500
X110500Y1112000
X115000Y1108500
X104500Y1095000
X109000Y1083500
X116500Y1076000
X103500Y1073500
X110500Y1064500
X91400Y1064100
X95500Y1064000
X116500Y1062500
X110500Y1051000
X116500Y1049000
X103500Y1042000
X110500Y1041500
X116500Y1035500
X111500Y1030000
X103500Y1028500
X117500Y1023500
X97250
X111500Y1020000
X104000Y1014000
X106500Y1008500
X117000
X114800Y1005000
X95500Y999000
X105500Y996000
X119000Y975000
X108500Y971000
Y964000
X105000Y958000
X99000Y953000
X110000Y949500
X117529Y948844
X115500Y930000
X93000Y925500
X115000Y920000
X107000Y918000
X96500Y916500
X94000Y910500
X103500Y909500
X113500
X116053Y903247
X96053
X107000Y903000
X102500Y893500
X117500Y893000
X90000
X95500Y841500
X90500Y831500
X115000Y813000
X114500Y805500
X107000Y802400
X114000Y800000
X107000Y798200
X106882Y794201
X113500Y792500
X115200Y784200
X115000Y773200
X116500Y752000
X115000Y704500
X103500Y695500
X108500
X99001Y694866
X119576Y687008
X98000Y674327
X107113Y674001
X102913Y673973
X119000Y673300
X100600Y670600
X90674Y663367
X108200Y655825
X112800Y653500
X90630Y602020
X103100Y587600
X117000Y530000
X100000Y519100
X110800Y512600
X100000Y512000
X110800Y506600
X100000Y506000
X110800Y500600
X100000Y500000
X110800Y494600
X100000Y494000
X110800Y488600
X100000Y488000
X110800Y482600
X99800Y482000
X99500Y473000
X111500
X117000Y471500
Y466000
Y460500
Y455000
Y449000
X98000Y426500
X107000
X102500
X111200Y426400
X118000Y424000
Y414000
X91900Y410500
X105500Y406500
X110500
X101500
X118000Y404000
Y396000
X101300Y390100
X111500Y390000
X105500
X118000Y386000
X94000Y320000
X102000Y312000
X94000
X104000Y304000
X94000
X96000Y296000
X106000
X114000
X95000Y155000
X105000
X118000Y154500
X95000Y143000
X105000
X118000Y142500
X95000Y134000
X105000Y125000
X95000
X118000Y124500
X119000Y109500
X105000Y55000
X118000Y54500
X115000Y45000
X105000
X95000
X135000
X125000
X145000
X135000Y50000
Y70000
X124000Y74500
X128500Y89000
X128700Y104200
X127700Y119200
X137200Y123600
X146500Y131859
X131000Y138100
Y150100
X147600Y150900
X129000Y160100
X138800Y162100
X137900Y171400
X130900Y259100
X131800Y289700
X142000Y291000
X141300Y298100
X143400Y318700
X143300Y343400
X134000Y386000
Y396000
Y404500
Y414000
Y424000
X145500Y427000
X142000Y432000
X130000
X131000Y447000
X136000
X122500Y450500
X135500Y454000
X130500
X122500Y457500
X130500Y461000
X135500
X122500Y463500
X130500Y468000
X135500
X122500Y469500
X135500Y474500
X130500
X121500Y475500
X129000Y485500
X136500
X120000
X144000Y486182
X137000Y493000
X144000Y493500
X129000
X120000
X144000Y501500
X129000
X137000
X120000
X129000Y509500
X120000
X137000Y510000
X129000Y517500
X137500
X120000
X144000
X120000Y523500
X137500
X129000
X144600Y533800
X147500Y551500
X141800Y559250
X140700Y576600
X145500Y604000
X148995Y658568
X134100Y674500
X121500Y683500
X120702Y690847
X124800Y696600
X129800Y696800
X120000Y717500
X120500Y732500
X125000Y734000
X130000Y736500
X125500Y741500
X125000Y751000
Y758500
X121000Y767900
X129000Y774500
X121000Y776000
X129500Y782000
X121500Y783500
X122500Y792500
X129500
X130000Y800000
X123000
Y808500
X129800Y813500
X123500Y816000
X124500Y825100
X129200Y830400
X134500Y840500
X123500Y842500
X140500Y846500
X145500Y856500
X124500Y858000
X125000Y868500
X124500Y876500
X137500
X145500Y885000
X134500Y885500
X126000Y892500
X146000Y893000
X135000
X127000Y903000
X137500
X135500Y909000
X124000
X143000Y910500
X120000Y916000
X135000Y918000
X144000Y919500
X125500Y920000
X135500Y927500
X144000Y929000
X126000Y930000
X133500Y938000
X141000Y938500
X125500Y944000
X126000Y954000
X124618Y959244
X130500Y966000
X125000Y967000
X136500
X124000Y971500
X135000Y975500
X134000Y990500
X146800Y1018900
X143900Y1022700
X120000Y1102000
Y1108000
X147500Y1165500
Y1186000
Y1221500
X146500Y1241500
X147000Y1265500
X124000Y1270000
X123800Y1283900
X147500Y1288000
X124000Y1298000
X147500Y1311000
X123800Y1311900
X124000Y1324000
X147500Y1332000
X123800Y1337900
X147000Y1348000
X124000Y1352000
X123800Y1365900
X147500Y1366500
X124000Y1376500
X147000Y1377000
X146500Y1417619
X132200Y1424800
X137000Y1429200
X133799Y1440699
X121338Y1452021
X149686Y1460007
X126600Y1461500
X148300Y1465000
X133500Y1467100
X124500Y1524000
X148000Y1528000
X136000
X129000Y1535000
X136000Y1536000
X122000Y1538000
X148000Y1542000
X136000
X129000Y1542500
X122000Y1546000
X136000Y1548000
X129000Y1549000
X148000Y1550000
X122000Y1552000
X136000Y1555000
X129000Y1555500
X122000Y1558000
X148000
X136000Y1562000
X129000Y1562500
X122000Y1564000
X148000
X128000Y1568000
X136000
X121800Y1569929
X122000Y1576000
Y1584000
Y1592000
Y1600000
X138500Y1606000
X148000
X128000
X146000Y1612000
X122000
X149000Y1632500
X127500Y1633000
X138000Y1634000
X127000Y1646000
X148000
X138000
X127500Y1659500
X137500
X148500Y1660000
X127500Y1669000
X141500Y1673000
X125000Y1679000
X122000Y1685500
X139000Y1696500
Y1712500
X138500Y1727500
X139000Y1800500
X120000Y1811500
X138000Y1824000
X120500Y1836500
X138500Y1839500
X120500Y1850500
X139000Y1851000
X122500Y1862500
X132000Y1892000
X124500Y1892403
X161000Y1901500
X160500Y1877500
X173000Y1852610
X161500Y1852500
X151500Y1851110
X179000Y1798500
X155500
X166500Y1798000
X152000Y1790110
X172768
X162000Y1790000
X156500Y1782000
X169000Y1781500
X173268Y1776000
X162500Y1773000
X152500Y1771110
X152000Y1725610
X158500Y1716500
X167500Y1716000
X152000Y1710610
X158500Y1705000
X168500
X152000Y1697110
X174268
X163000Y1697000
X178000Y1659500
X159000
X170000
X166000Y1646000
X176000
X158000
X159000Y1632500
X167500
X176000Y1632000
X164000Y1606000
X172000
X156000
X150500Y1600000
X156500
X150500Y1591000
X156500
X156000Y1582000
X150500
X150000Y1576000
X156000
Y1570000
X150000
X166898Y1567102
X154000Y1564000
X161300Y1563100
X169500Y1561500
X170000Y1555000
Y1548500
X161400Y1543500
X170000Y1541000
X168500Y1533500
Y1526000
X174000Y1522000
Y1515500
X174500Y1509500
Y1503500
X152500Y1456000
X173375Y1432500
X164500Y1299500
X165000Y1264500
X161500Y1227500
X178644Y1202519
X163344Y1181200
X155000Y1130500
X177102Y1129800
X171502Y1129547
X155000Y1125000
Y1120000
X154600Y1111000
X158595Y1110789
X170000Y1103000
X157000Y1101500
X165000Y1097000
X170000Y1089500
X159500Y1087500
X173000Y1082000
X166000Y1080000
X158500Y1075800
X175000Y1072500
X171000Y1068000
X160500Y1067000
X175000Y1059000
X160500Y1053500
X171000Y1046000
X164700Y1033600
X171000Y1032500
X166300Y1021300
X176000Y1018500
X174000Y1012400
X153500Y941000
X154500Y926500
X154700Y909700
X156500Y889000
X156300Y877200
X157500Y858000
X177500Y826500
X171500Y819500
X177500Y812000
X163500Y805500
X178000Y797500
X169000Y795500
X175000Y786500
X165000Y786000
X173500Y777500
Y764000
X172000Y757500
X169100Y722100
X176000Y679000
X165500Y677500
X176000Y665500
X151432Y661741
X162300Y659100
X167300Y653800
X159700Y652000
X165600Y630269
X170349Y619949
X152700Y618803
X175800Y617635
X164950Y615700
X150500Y596000
X171600Y595400
X153500Y574359
X174900Y523300
X156800Y515400
X173700Y513900
X156800Y506900
X173500Y506000
X157100Y500000
X173600Y498800
X169200Y482800
X161900Y463300
X162000Y457600
X161900Y451600
X161600Y445900
X162000Y432000
X174500
X150000Y424000
Y414000
Y404000
Y396000
Y386000
X164000Y316000
X174000
X172000Y310000
X176000Y302000
X166000
X151300Y298200
X172000Y296000
X162000
X173500Y151500
X165300Y145200
X174500Y143500
X176000Y131000
X167000Y130500
X170500Y120500
X154000Y105500
X171500
X165500Y95500
X153000Y90500
X154000Y75500
X164000Y55500
X174000
X165000Y45000
X175000
X155000
X185000
X195000
X200000Y55000
X194000Y55500
X184000
X200000Y65000
Y75000
Y85000
Y100000
X190500Y105000
X180500Y112000
X200000Y120000
X189500
X187500Y130500
X200000Y140000
X186000Y143000
X185500Y151500
X197500
X191900Y167700
X201089Y181700
X191700Y186500
X200500Y195900
X191600Y206900
X201500Y208000
X191800Y221100
X201000Y222500
X191800Y234900
X200500Y235000
X191900Y244600
X202000Y254000
Y264000
Y274000
X201089Y282600
X202000Y295000
X182000Y296000
X184000Y303000
X201089Y305500
X182000Y310000
X201089Y315500
X184500Y325500
X202000Y328000
X187500Y338000
X202000Y340000
X180850Y348800
X202000Y353000
X181100Y364050
X188500Y364100
X202000Y366500
X188300Y368600
X181800Y369000
X201500Y378000
X201089Y388400
X192600Y392600
X192471Y397355
X201500Y397500
X192400Y401900
X201089Y407000
X192300Y410950
X192409Y417655
X200000Y420500
X186600Y425750
X201000Y430500
X200500Y437500
X190239Y447449
X195600Y447500
X195500Y453500
X190400
X189900Y460500
X195000
X189900Y467500
X195000
X188500Y474500
X194500
X199500Y489400
X192000Y490000
Y498000
X186500
X200300Y498100
X199800Y506000
X192000
X186500
X192000Y513500
X186500
X200100Y513600
X186500Y519000
X193600Y519100
X201200Y519200
X190200Y523400
X201089Y523500
X192400Y529400
X201089Y529500
X201500Y535000
X191900Y538200
X192000Y543500
X201500Y544500
X182600Y546900
X190500Y550500
X201500Y552500
X201089Y558000
X201500Y564000
X201089Y570600
X202000Y578000
X194400Y586000
X202000
X180500Y595000
X202000
X193700
X202000Y607500
X194000Y615000
X201500Y621500
X180500Y627771
X194000Y628500
X192600Y633000
X196500Y641500
X192500Y645000
X202000Y650500
X192500Y658500
X184700Y663900
X195000Y670000
X185000Y673500
X202000Y676500
X193100Y679000
X197500Y685000
X188100Y689100
X191500Y692500
X183500Y698000
X197000Y704000
X184500Y708500
X202000Y710000
X191500Y710500
X181000Y715500
X196000Y718500
X191500Y724000
X181000Y729000
X181500Y738500
X195500Y739000
X202000Y740500
X182500Y745000
X191500Y746500
X197500Y753000
X182500Y758500
X191500Y760000
X202000Y765000
X181700Y768400
X194500Y769000
Y782500
X187900Y785300
X202000Y786000
X196000Y789500
X196500Y797000
X202000Y807500
X197000Y815000
X190000Y823500
X196800Y828500
X190500Y831000
X201500Y835500
X192500Y839500
X185000Y843500
X192500Y853000
X192000Y865500
X184500
X192000Y879000
X184500
X187000Y891000
X194000Y893500
Y907000
X185000Y917500
X192000Y921000
Y934500
Y948500
X182000Y950500
X192000Y962000
X192500Y972000
Y985500
X184000Y987500
X195500Y1001000
Y1014500
X182000Y1016000
X193500Y1029000
X182000Y1029500
X182500Y1041500
X193500Y1042500
X181000Y1051000
X190000Y1052000
X195000Y1061000
X183500Y1065500
X195000Y1074500
X181000Y1079500
X195000Y1086500
X187500Y1090000
X201000Y1093000
X181000Y1098500
X194500Y1100500
X187500Y1103500
X201000Y1106500
X181000Y1112500
X183500Y1241500
X191800Y1280900
X192500Y1533000
Y1543500
Y1554000
Y1562500
X182500Y1584500
X196500Y1586000
X182500Y1592000
X196500Y1595000
X182500Y1599400
X192500Y1617000
Y1626500
Y1634000
Y1664000
Y1670500
X198000Y1691500
X184500Y1696500
X182000Y1704000
X198500Y1713500
X181500Y1716500
X182000Y1726000
X198000Y1735500
X185000Y1738500
X198000Y1754000
X183600Y1765100
X197500Y1776500
X186000Y1790000
X197500Y1800500
X185500Y1804500
X198000Y1818500
X183100Y1838300
X198000Y1838500
X185000Y1852500
X198500Y1859500
X195000Y1874000
X200000Y1882000
X201500Y1900500
X195500Y1905000
X201000Y1923000
X190500Y1924000
T03
X31299Y210866
Y220866
Y230866
Y338563
Y348563
Y358563
Y903917
Y913917
Y923917
Y1044587
Y1054587
Y1064587
Y1609941
Y1619941
Y1629941
Y1737638
Y1747638
Y1757638
T04
X15906Y48110
Y58110
Y68110
Y78110
Y88110
Y481339
Y491339
Y501339
Y511339
Y521339
Y741181
Y751181
Y761181
Y771181
Y781181
Y1187323
Y1197323
Y1207323
Y1217323
Y1227323
X165000Y1370500
Y1380500
Y1390500
X15906Y1447165
Y1457165
Y1467165
Y1477165
Y1487165
X138937Y1778819
X128937
X118937
X15906Y1880394
Y1890394
Y1900394
Y1910394
Y1920394
T05
X80709Y161889
Y171889
Y181889
Y191889
Y204409
Y214409
Y224409
Y234409
Y244409
Y256929
Y266929
Y276929
Y286929
X90709
Y276929
Y266929
Y256929
Y244409
Y234409
Y224409
Y214409
Y204409
Y191889
Y181889
Y171889
Y161889
X100709
Y171889
Y181889
Y191889
Y204409
Y214409
Y224409
Y234409
Y244409
Y256929
Y266929
Y276929
Y286929
X110709
Y276929
Y266929
Y256929
Y244409
Y234409
Y224409
Y214409
Y204409
Y191889
Y181889
Y171889
Y161889
X149606
Y171889
Y181889
Y191889
Y204409
Y214409
Y224409
Y234409
Y244409
Y256929
Y266929
Y276929
Y286929
X159606
Y276929
Y266929
Y256929
Y244409
Y234409
Y224409
Y214409
Y204409
Y191889
Y181889
Y171889
Y161889
X169606
Y171889
Y181889
Y191889
Y204409
Y214409
Y224409
Y234409
Y244409
Y256929
Y266929
Y276929
Y286929
X179606
Y276929
Y266929
Y256929
Y244409
Y234409
Y224409
Y214409
Y204409
Y191889
Y181889
Y171889
Y161889
T06
X179134Y78740
X179133Y570866
X27559Y629921
X179134Y1161417
X17716Y1338583
X27559Y1811023
T07
X27559Y157480
X179134Y1889764
T08
X178937Y1328740
X161417Y1747835
X96457
Y1823031
X161417
T09
X80709Y139409
X149606
Y309409
X80709
T10
X47244Y68110
Y501338
Y761181
Y1207323
Y1467165
Y1900393
T11
X80709Y119409
X149606
Y329409
X80709
T12
X-222440Y19685
X643700
Y1948818
X-222440
T13
X29921Y24803
Y111417
Y458031
Y544646
Y717874
Y804488
X30000Y1164000
X29921Y1250630
Y1423858
Y1510472
Y1857086
Y1943701
M30
